(kicad_pcb
	(version 20260206)
	(generator "pcbnew")
	(generator_version "10.0")
	(general
		(thickness 1.6)
		(legacy_teardrops no)
	)
	(paper "A4")
	(title_block
		(title "03242023_DA0F0TMBIJ0_F0T_Motherboard_J_brd_V01_OCP.brd")
		(comment 1 "Grand Teton / footprints 2683-2686 of 6105")
	)
	(layers
		(0 "F.Cu" signal "TOP")
		(4 "In1.Cu" signal "GND")
		(6 "In2.Cu" signal "IN1")
		(8 "In3.Cu" signal "GND1")
		(10 "In4.Cu" signal "IN2")
		(12 "In5.Cu" signal "GND2")
		(14 "In6.Cu" signal "IN3")
		(16 "In7.Cu" signal "GND3")
		(18 "In8.Cu" signal "VCC")
		(20 "In9.Cu" signal "VCC1")
		(22 "In10.Cu" signal "GND4")
		(24 "In11.Cu" signal "IN4")
		(26 "In12.Cu" signal "GND5")
		(28 "In13.Cu" signal "IN5")
		(30 "In14.Cu" signal "GND6")
		(32 "In15.Cu" signal "IN6")
		(34 "In16.Cu" signal "GND7")
		(2 "B.Cu" signal "BOTTOM")
		(9 "F.Adhes" user "F.Adhesive")
		(11 "B.Adhes" user "B.Adhesive")
		(13 "F.Paste" user "Package Geometry/Pastemask Top")
		(15 "B.Paste" user "Package Geometry/Pastemask Bottom")
		(5 "F.SilkS" user "Ref Des/Silkscreen Top")
		(7 "B.SilkS" user "Ref Des/Silkscreen Bottom")
		(1 "F.Mask" user "Board Geometry/Soldermask Top")
		(3 "B.Mask" user "Board Geometry/Soldermask Bottom")
		(17 "Dwgs.User" user "User.Drawings")
		(19 "Cmts.User" user "User.Comments")
		(21 "Eco1.User" user "User.Eco1")
		(23 "Eco2.User" user "User.Eco2")
		(25 "Edge.Cuts" user "Board Geometry/Outline")
		(27 "Margin" user)
		(31 "F.CrtYd" user "Package Geometry/Place Bound Top")
		(29 "B.CrtYd" user "Package Geometry/Place Bound Bottom")
		(35 "F.Fab" user "Ref Des/Assembly Top")
		(33 "B.Fab" user "Ref Des/Assembly Bottom")
	)
	(footprint ""
		(layer "F.Cu")
		(at 137.800334 -342.917018)
		(property "Reference" "PU23_P1_8"
			(at 0.53848 -6.47827 0)
			(unlocked yes)
			(layer "F.SilkS")
			(effects
				(font
					(size 0.7874 0.5842)
					(thickness 0.1524)
				)
				(justify left)
			)
		)
		(property "Value" ""
			(at 0 0 0)
			(layer "F.Fab")
			(effects
				(font
					(size 1.27 1.27)
				)
			)
		)
		(duplicate_pad_numbers_are_jumpers no)
		(fp_line
			(start -2.500122 -2.999994)
			(end -2.24409 -2.999994)
			(stroke
				(width 0.1524)
				(type default)
			)
			(layer "F.SilkS")
		)
		(fp_line
			(start -2.500122 -2.529078)
			(end -2.500122 -2.999994)
			(stroke
				(width 0.1524)
				(type default)
			)
			(layer "F.SilkS")
		)
		(fp_line
			(start -2.500122 0.6604)
			(end -2.500122 0.229108)
			(stroke
				(width 0.1524)
				(type default)
			)
			(layer "F.SilkS")
		)
		(fp_line
			(start -2.500122 2.999994)
			(end -2.500122 2.339594)
			(stroke
				(width 0.1524)
				(type default)
			)
			(layer "F.SilkS")
		)
		(fp_line
			(start -2.2987 2.999994)
			(end -2.500122 2.999994)
			(stroke
				(width 0.1524)
				(type default)
			)
			(layer "F.SilkS")
		)
		(fp_line
			(start 2.31394 -2.999994)
			(end 2.500122 -2.999994)
			(stroke
				(width 0.1524)
				(type default)
			)
			(layer "F.SilkS")
		)
		(fp_line
			(start 2.500122 -2.999994)
			(end 2.500122 -2.44348)
			(stroke
				(width 0.1524)
				(type default)
			)
			(layer "F.SilkS")
		)
		(fp_line
			(start 2.500122 2.339594)
			(end 2.500122 2.999994)
			(stroke
				(width 0.1524)
				(type default)
			)
			(layer "F.SilkS")
		)
		(fp_line
			(start 2.500122 2.999994)
			(end 2.2987 2.999994)
			(stroke
				(width 0.1524)
				(type default)
			)
			(layer "F.SilkS")
		)
		(fp_poly
			(pts
				(xy -2.234946 -3.650488) (xy -2.742946 -2.634488) (xy -3.250946 -3.650488)
			)
			(stroke
				(width 0)
				(type default)
			)
			(fill yes)
			(layer "F.SilkS")
		)
		(fp_line
			(start -2.500122 -2.999994)
			(end 2.500122 -2.999994)
			(stroke
				(width 0.1)
				(type default)
			)
			(layer "F.Fab")
		)
		(fp_line
			(start -2.500122 2.999994)
			(end -2.500122 -2.999994)
			(stroke
				(width 0.1)
				(type default)
			)
			(layer "F.Fab")
		)
		(fp_line
			(start 2.500122 -2.999994)
			(end 2.500122 2.999994)
			(stroke
				(width 0.1)
				(type default)
			)
			(layer "F.Fab")
		)
		(fp_line
			(start 2.500122 2.999994)
			(end -2.500122 2.999994)
			(stroke
				(width 0.1)
				(type default)
			)
			(layer "F.Fab")
		)
		(fp_poly
			(pts
				(xy -4.218432 -2.783078) (xy -4.218432 -1.767078) (xy -3.202432 -2.275078)
			)
			(stroke
				(width 0)
				(type default)
			)
			(fill yes)
			(layer "F.Fab")
		)
		(pad "1" smd rect
			(at -2.400046 -2.275078 90)
			(size 0.2286 0.6096)
			(layers "F.Cu" "F.Mask" "F.Paste")
			(net "PVCCIN_CPU1_VOS8")
		)
		(pad "2" smd rect
			(at -2.400046 -1.82499 90)
			(size 0.2286 0.6096)
			(layers "F.Cu" "F.Mask" "F.Paste")
			(net "GND")
		)
		(pad "3" smd rect
			(at -2.400046 -1.374902 90)
			(size 0.2286 0.6096)
			(layers "F.Cu" "F.Mask" "F.Paste")
			(net "PVCCIN_CPU1_VDD8")
		)
		(pad "4" smd rect
			(at -2.400046 -0.925068 90)
			(size 0.2286 0.6096)
			(layers "F.Cu" "F.Mask" "F.Paste")
			(net "PVCCIN_CPU1_PVCC")
		)
		(pad "5" smd rect
			(at -2.400046 -0.47498 90)
			(size 0.2286 0.6096)
			(layers "F.Cu" "F.Mask" "F.Paste")
			(net "GND")
		)
		(pad "6" smd rect
			(at -2.400046 -0.024892 90)
			(size 0.2286 0.6096)
			(layers "F.Cu" "F.Mask" "F.Paste")
			(net "Net_8541")
		)
		(pad "7_9-20_24" smd circle
			(at 0 1.150112 90)
			(size 0 0)
			(layers "F.Cu" "F.Mask" "F.Paste")
			(net "GND")
		)
		(pad "10_19" smd rect
			(at 0 2.899918 90)
			(size 0.6096 4.318)
			(layers "F.Cu" "F.Mask" "F.Paste")
			(net "SW_PVCCIN_CPU1_SW8")
		)
		(pad "25_29" smd rect
			(at 1.549908 -1.279906 270)
			(size 2.0574 2.3114)
			(layers "F.Cu" "F.Mask" "F.Paste")
			(net "SW_P12V_PVCCIN_CPU1_FLT")
		)
		(pad "30" smd rect
			(at 2.05994 -2.899918)
			(size 0.2286 0.6096)
			(layers "F.Cu" "F.Mask" "F.Paste")
			(net "SW_P12V_PVCCIN_CPU1_FLT")
		)
		(pad "31" smd rect
			(at 1.610106 -2.899918)
			(size 0.2286 0.6096)
			(layers "F.Cu" "F.Mask" "F.Paste")
			(net "Net_8542")
		)
		(pad "32" smd rect
			(at 1.160018 -2.899918)
			(size 0.2286 0.6096)
			(layers "F.Cu" "F.Mask" "F.Paste")
			(net "SW_PVCCIN_CPU1_BOOTR8")
		)
		(pad "33" smd rect
			(at 0.70993 -2.899918)
			(size 0.2286 0.6096)
			(layers "F.Cu" "F.Mask" "F.Paste")
			(net "SW_PVCCIN_CPU1_BOOT8")
		)
		(pad "34" smd rect
			(at 0.260096 -2.899918)
			(size 0.2286 0.6096)
			(layers "F.Cu" "F.Mask" "F.Paste")
			(net "PVCCIN_CPU1_PWM8")
		)
		(pad "35" smd rect
			(at -0.189992 -2.899918)
			(size 0.2286 0.6096)
			(layers "F.Cu" "F.Mask" "F.Paste")
			(net "PVCCIN_CPU1_VDD8")
		)
		(pad "36" smd rect
			(at -0.64008 -2.899918)
			(size 0.2286 0.6096)
			(layers "F.Cu" "F.Mask" "F.Paste")
			(net "PVCCIN_CPU1_ATSEN")
		)
		(pad "37" smd rect
			(at -1.089914 -2.899918)
			(size 0.2286 0.6096)
			(layers "F.Cu" "F.Mask" "F.Paste")
			(net "PVCCIN_CPU1_LSET8")
		)
		(pad "38" smd rect
			(at -1.540002 -2.899918)
			(size 0.2286 0.6096)
			(layers "F.Cu" "F.Mask" "F.Paste")
			(net "PVCCIN_CPU1_IMON8")
		)
		(pad "39" smd rect
			(at -1.99009 -2.899918)
			(size 0.2286 0.6096)
			(layers "F.Cu" "F.Mask" "F.Paste")
			(net "PVCCIN_CPU1_VREF")
		)
		(pad "40" smd rect
			(at -0.87503 -1.27508)
			(size 1.7526 1.9558)
			(layers "F.Cu" "F.Mask" "F.Paste")
			(net "GND")
		)
		(pad "41" smd rect
			(at -1.525016 0.249936 270)
			(size 0.3048 0.4572)
			(layers "F.Cu" "F.Mask" "F.Paste")
			(net "Net_8540")
		)
		(zone
			(layer "F.Cu")
			(hatch none 0.5)
			(connect_pads
				(clearance 0)
			)
			(min_thickness 0.25)
			(keepout
				(tracks not_allowed)
				(vias allowed)
				(pads allowed)
				(copperpour not_allowed)
				(footprints allowed)
			)
			(placement
				(enabled no)
				(sheetname "")
			)
			(fill
				(thermal_gap 0.5)
				(thermal_bridge_width 0.5)
				(island_removal_mode 0)
			)
			(polygon
				(pts
					(xy 135.300212 -339.917024) (xy 135.300212 -340.666324) (xy 140.300456 -340.666324) (xy 140.300456 -339.917024)
					(xy 140.010134 -339.917024) (xy 140.010134 -340.3727) (xy 135.590534 -340.3727) (xy 135.590534 -339.917024)
				)
			)
		)
		(zone
			(layer "F.Cu")
			(hatch none 0.5)
			(connect_pads
				(clearance 0)
			)
			(min_thickness 0.25)
			(keepout
				(tracks not_allowed)
				(vias allowed)
				(pads allowed)
				(copperpour not_allowed)
				(footprints allowed)
			)
			(placement
				(enabled no)
				(sheetname "")
			)
			(fill
				(thermal_gap 0.5)
				(thermal_bridge_width 0.5)
				(island_removal_mode 0)
			)
			(polygon
				(pts
					(xy 135.755888 -343.233248) (xy 135.998204 -343.233248) (xy 135.998204 -343.163398) (xy 136.78662 -343.163398)
					(xy 136.78662 -342.854788) (xy 136.849612 -342.854788) (xy 136.849612 -342.167718) (xy 135.300212 -342.167718)
					(xy 135.300212 -342.62441) (xy 135.995918 -342.62441) (xy 135.995918 -342.463882) (xy 136.554718 -342.463882)
					(xy 136.554718 -342.870282) (xy 135.995918 -342.870282) (xy 135.995918 -342.64981) (xy 135.300212 -342.64981)
					(xy 135.300212 -342.77681) (xy 135.755888 -342.77681)
				)
			)
		)
	)
	(footprint ""
		(layer "F.Cu")
		(at 95.095314 -419.722554 90)
		(property "Reference" "R3503"
			(at 0 0 90)
			(layer "F.SilkS")
			(hide yes)
			(effects
				(font
					(size 1.27 1.27)
				)
			)
		)
		(property "Value" ""
			(at 0 0 90)
			(layer "F.Fab")
			(effects
				(font
					(size 1.27 1.27)
				)
			)
		)
		(duplicate_pad_numbers_are_jumpers no)
		(fp_line
			(start 0.7874 -0.4064)
			(end 0.7874 0.4064)
			(stroke
				(width 0.1524)
				(type default)
			)
			(layer "F.SilkS")
		)
		(fp_line
			(start -0.7874 -0.4064)
			(end 0.7874 -0.4064)
			(stroke
				(width 0.1524)
				(type default)
			)
			(layer "F.SilkS")
		)
		(fp_line
			(start 0.7874 0.4064)
			(end -0.7874 0.4064)
			(stroke
				(width 0.1524)
				(type default)
			)
			(layer "F.SilkS")
		)
		(fp_line
			(start -0.7874 0.4064)
			(end -0.7874 -0.4064)
			(stroke
				(width 0.1524)
				(type default)
			)
			(layer "F.SilkS")
		)
		(fp_line
			(start -0.12065 -0.305054)
			(end -0.12065 -0.2794)
			(stroke
				(width 0.1)
				(type default)
			)
			(layer "F.Fab")
		)
		(fp_line
			(start -0.67945 -0.305054)
			(end -0.12065 -0.305054)
			(stroke
				(width 0.1)
				(type default)
			)
			(layer "F.Fab")
		)
		(fp_line
			(start 0.67945 -0.3048)
			(end 0.67945 0.3048)
			(stroke
				(width 0.1)
				(type default)
			)
			(layer "F.Fab")
		)
		(fp_line
			(start 0.12065 -0.3048)
			(end 0.67945 -0.3048)
			(stroke
				(width 0.1)
				(type default)
			)
			(layer "F.Fab")
		)
		(fp_line
			(start 0.12065 -0.2794)
			(end 0.12065 -0.3048)
			(stroke
				(width 0.1)
				(type default)
			)
			(layer "F.Fab")
		)
		(fp_line
			(start -0.12065 -0.2794)
			(end 0.12065 -0.2794)
			(stroke
				(width 0.1)
				(type default)
			)
			(layer "F.Fab")
		)
		(fp_line
			(start 0.120396 0.2794)
			(end -0.12065 0.2794)
			(stroke
				(width 0.1)
				(type default)
			)
			(layer "F.Fab")
		)
		(fp_line
			(start -0.12065 0.2794)
			(end -0.12065 0.3048)
			(stroke
				(width 0.1)
				(type default)
			)
			(layer "F.Fab")
		)
		(fp_line
			(start 0.67945 0.3048)
			(end 0.120396 0.3048)
			(stroke
				(width 0.1)
				(type default)
			)
			(layer "F.Fab")
		)
		(fp_line
			(start 0.120396 0.3048)
			(end 0.120396 0.2794)
			(stroke
				(width 0.1)
				(type default)
			)
			(layer "F.Fab")
		)
		(fp_line
			(start -0.12065 0.3048)
			(end -0.67945 0.3048)
			(stroke
				(width 0.1)
				(type default)
			)
			(layer "F.Fab")
		)
		(fp_line
			(start -0.67945 0.3048)
			(end -0.67945 -0.305054)
			(stroke
				(width 0.1)
				(type default)
			)
			(layer "F.Fab")
		)
		(pad "1" smd circle
			(at -0.40005 0 90)
			(size 0 0)
			(layers "F.Cu" "F.Mask" "F.Paste")
			(net "P3V3_AUX")
		)
		(pad "2" smd circle
			(at 0.40005 0 90)
			(size 0 0)
			(layers "F.Cu" "F.Mask" "F.Paste")
			(net "GPU_FPGA_EROT_FATALERR")
		)
	)
	(footprint ""
		(layer "F.Cu")
		(at 385.858004 -333.55153)
		(property "Reference" "PL7"
			(at 0.123444 6.322314 0)
			(unlocked yes)
			(layer "F.SilkS")
			(effects
				(font
					(size 0.7874 0.5842)
					(thickness 0.1524)
				)
				(justify left)
			)
		)
		(property "Value" ""
			(at 0 0 0)
			(layer "F.Fab")
			(effects
				(font
					(size 1.27 1.27)
				)
			)
		)
		(duplicate_pad_numbers_are_jumpers no)
		(fp_line
			(start -3.750056 -5.500116)
			(end -2.393442 -5.500116)
			(stroke
				(width 0.1524)
				(type default)
			)
			(layer "F.SilkS")
		)
		(fp_line
			(start -3.750056 5.500116)
			(end -3.750056 -5.500116)
			(stroke
				(width 0.1524)
				(type default)
			)
			(layer "F.SilkS")
		)
		(fp_line
			(start -2.393442 5.500116)
			(end -3.750056 5.500116)
			(stroke
				(width 0.1524)
				(type default)
			)
			(layer "F.SilkS")
		)
		(fp_line
			(start 2.393442 5.500116)
			(end 3.750056 5.500116)
			(stroke
				(width 0.1524)
				(type default)
			)
			(layer "F.SilkS")
		)
		(fp_line
			(start 3.750056 -5.500116)
			(end 2.393442 -5.500116)
			(stroke
				(width 0.1524)
				(type default)
			)
			(layer "F.SilkS")
		)
		(fp_line
			(start 3.750056 5.500116)
			(end 3.750056 -5.500116)
			(stroke
				(width 0.1524)
				(type default)
			)
			(layer "F.SilkS")
		)
		(fp_poly
			(pts
				(xy -4.8768 -5.720588) (xy -3.8608 -5.212588) (xy -4.8768 -4.704588)
			)
			(stroke
				(width 0)
				(type default)
			)
			(fill yes)
			(layer "F.SilkS")
		)
		(fp_line
			(start -3.750056 -5.500116)
			(end -3.750056 5.500116)
			(stroke
				(width 0.1)
				(type default)
			)
			(layer "F.Fab")
		)
		(fp_line
			(start -3.750056 5.500116)
			(end 3.750056 5.500116)
			(stroke
				(width 0.1)
				(type default)
			)
			(layer "F.Fab")
		)
		(fp_line
			(start 3.750056 -5.500116)
			(end -3.750056 -5.500116)
			(stroke
				(width 0.1)
				(type default)
			)
			(layer "F.Fab")
		)
		(fp_line
			(start 3.750056 5.500116)
			(end 3.750056 -5.500116)
			(stroke
				(width 0.1)
				(type default)
			)
			(layer "F.Fab")
		)
		(fp_poly
			(pts
				(xy -4.9276 -4.757928) (xy -4.9276 -3.741928) (xy -3.9116 -4.249928)
			)
			(stroke
				(width 0)
				(type default)
			)
			(fill yes)
			(layer "F.Fab")
		)
		(pad "1" smd rect
			(at 0 -4.249928 270)
			(size 2.413 4.5212)
			(layers "F.Cu" "F.Mask" "F.Paste")
			(net "SW_PVCCIN_CPU0_SW8")
		)
		(pad "2" smd rect
			(at 0 -1.175004 270)
			(size 1.3716 4.5212)
			(layers "F.Cu" "F.Mask" "F.Paste")
			(net "IND_P0_CPL8")
		)
		(pad "3" smd rect
			(at 0 1.175004 270)
			(size 1.3716 4.5212)
			(layers "F.Cu" "F.Mask" "F.Paste")
			(net "GND")
		)
		(pad "4" smd rect
			(at 0 4.249928 270)
			(size 2.413 4.5212)
			(layers "F.Cu" "F.Mask" "F.Paste")
			(net "PVCCIN_CPU0")
		)
	)
	(footprint ""
		(layer "F.Cu")
		(at 131.014216 -66.919602 90)
		(property "Reference" "R804"
			(at 0 0 90)
			(layer "F.SilkS")
			(hide yes)
			(effects
				(font
					(size 1.27 1.27)
				)
			)
		)
		(property "Value" ""
			(at 0 0 90)
			(layer "F.Fab")
			(effects
				(font
					(size 1.27 1.27)
				)
			)
		)
		(duplicate_pad_numbers_are_jumpers no)
		(fp_line
			(start 0.7874 -0.4064)
			(end 0.7874 0.4064)
			(stroke
				(width 0.1524)
				(type default)
			)
			(layer "F.SilkS")
		)
		(fp_line
			(start -0.7874 -0.4064)
			(end 0.7874 -0.4064)
			(stroke
				(width 0.1524)
				(type default)
			)
			(layer "F.SilkS")
		)
		(fp_line
			(start 0.7874 0.4064)
			(end -0.7874 0.4064)
			(stroke
				(width 0.1524)
				(type default)
			)
			(layer "F.SilkS")
		)
		(fp_line
			(start -0.7874 0.4064)
			(end -0.7874 -0.4064)
			(stroke
				(width 0.1524)
				(type default)
			)
			(layer "F.SilkS")
		)
		(fp_line
			(start -0.12065 -0.305054)
			(end -0.12065 -0.2794)
			(stroke
				(width 0.1)
				(type default)
			)
			(layer "F.Fab")
		)
		(fp_line
			(start -0.67945 -0.305054)
			(end -0.12065 -0.305054)
			(stroke
				(width 0.1)
				(type default)
			)
			(layer "F.Fab")
		)
		(fp_line
			(start 0.67945 -0.3048)
			(end 0.67945 0.3048)
			(stroke
				(width 0.1)
				(type default)
			)
			(layer "F.Fab")
		)
		(fp_line
			(start 0.12065 -0.3048)
			(end 0.67945 -0.3048)
			(stroke
				(width 0.1)
				(type default)
			)
			(layer "F.Fab")
		)
		(fp_line
			(start 0.12065 -0.2794)
			(end 0.12065 -0.3048)
			(stroke
				(width 0.1)
				(type default)
			)
			(layer "F.Fab")
		)
		(fp_line
			(start -0.12065 -0.2794)
			(end 0.12065 -0.2794)
			(stroke
				(width 0.1)
				(type default)
			)
			(layer "F.Fab")
		)
		(fp_line
			(start 0.120396 0.2794)
			(end -0.12065 0.2794)
			(stroke
				(width 0.1)
				(type default)
			)
			(layer "F.Fab")
		)
		(fp_line
			(start -0.12065 0.2794)
			(end -0.12065 0.3048)
			(stroke
				(width 0.1)
				(type default)
			)
			(layer "F.Fab")
		)
		(fp_line
			(start 0.67945 0.3048)
			(end 0.120396 0.3048)
			(stroke
				(width 0.1)
				(type default)
			)
			(layer "F.Fab")
		)
		(fp_line
			(start 0.120396 0.3048)
			(end 0.120396 0.2794)
			(stroke
				(width 0.1)
				(type default)
			)
			(layer "F.Fab")
		)
		(fp_line
			(start -0.12065 0.3048)
			(end -0.67945 0.3048)
			(stroke
				(width 0.1)
				(type default)
			)
			(layer "F.Fab")
		)
		(fp_line
			(start -0.67945 0.3048)
			(end -0.67945 -0.305054)
			(stroke
				(width 0.1)
				(type default)
			)
			(layer "F.Fab")
		)
		(pad "1" smd circle
			(at -0.40005 0 90)
			(size 0 0)
			(layers "F.Cu" "F.Mask" "F.Paste")
			(net "JTAG_PLD_TDO_R")
		)
		(pad "2" smd circle
			(at 0.40005 0 90)
			(size 0 0)
			(layers "F.Cu" "F.Mask" "F.Paste")
			(net "JTAG_BMC_PLD_TDO")
		)
	)
)
